(kicad_pcb
	(version 20241229)
	(generator "pcbnew")
	(generator_version "9.0")
	(general
		(thickness 1.292)
		(legacy_teardrops no)
	)
	(paper "A4")
	(title_block
		(title "LPDDR5 Testbed")
		(date "2023-12-19")
		(rev "1.0.0")
		(comment 9 "footprint 16 of 160 (J1), pads 95-187 of 264")
	)
	(layers
		(0 "F.Cu" signal)
		(4 "In1.Cu" power)
		(6 "In2.Cu" power)
		(8 "In3.Cu" signal)
		(10 "In4.Cu" signal)
		(2 "B.Cu" signal)
		(9 "F.Adhes" user "F.Adhesive")
		(11 "B.Adhes" user "B.Adhesive")
		(13 "F.Paste" user)
		(15 "B.Paste" user)
		(5 "F.SilkS" user "F.Silkscreen")
		(7 "B.SilkS" user "B.Silkscreen")
		(1 "F.Mask" user)
		(3 "B.Mask" user)
		(17 "Dwgs.User" user "User.Drawings")
		(19 "Cmts.User" user "User.Comments")
		(21 "Eco1.User" user "User.Eco1")
		(23 "Eco2.User" user "User.Eco2")
		(25 "Edge.Cuts" user)
		(27 "Margin" user)
		(31 "F.CrtYd" user "F.Courtyard")
		(29 "B.CrtYd" user "B.Courtyard")
		(35 "F.Fab" user)
		(33 "B.Fab" user)
	)
	(footprint "lpddr5-testbed-footprints:Edge_Conn_Bus_DDR5_SODIMM"
		(locked yes)
		(layer "F.Cu")
		(at 99.975 100)
		(descr "SODIMM DDR5 Edge Connector")
		(tags "SODIMM DDR5 Edge Connector")
		(property "Reference" "J1"
			(at 0 -4.2 0)
			(unlocked yes)
			(layer "F.SilkS")
			(effects
				(font
					(size 0.7 0.7)
					(thickness 0.15)
				)
				(justify left bottom)
			)
		)
		(property "Value" "Edge_Conn_Bus_DDR5_SODIMM_1xDetectPin"
			(at 0 1 0)
			(layer "F.Fab")
			(effects
				(font
					(size 0.7 0.7)
					(thickness 0.15)
				)
				(justify left bottom)
			)
		)
		(property "Author" "Antmicro"
			(at 0 0 0)
			(layer "F.Fab")
			(hide yes)
			(effects
				(font
					(size 1 1)
					(thickness 0.15)
				)
			)
		)
		(property "License" "Apache-2.0"
			(at 0 0 0)
			(layer "F.Fab")
			(hide yes)
			(effects
				(font
					(size 1 1)
					(thickness 0.15)
				)
			)
		)
		(property "MPN" ""
			(at 0 0 0)
			(layer "F.Fab")
			(hide yes)
			(effects
				(font
					(size 1 1)
					(thickness 0.15)
				)
			)
		)
		(property "Manufacturer" ""
			(at 0 0 0)
			(layer "F.Fab")
			(hide yes)
			(effects
				(font
					(size 1 1)
					(thickness 0.15)
				)
			)
		)
		(sheetname "SODIMM")
		(sheetfile "sodim.kicad_sch")
		(attr exclude_from_pos_files)
		(pad "93" smd rect
			(at 24.425 -1.375)
			(size 0.35 2.35)
			(layers "F.Cu" "F.Mask")
			(net 14 "GND")
			(pinfunction "VSS")
			(pintype "passive")
		)
		(pad "94" smd rect
			(at 24.675 -1.375 180)
			(size 0.35 2.35)
			(layers "B.Cu" "B.Mask")
			(net 14 "GND")
			(pinfunction "VSS")
			(pintype "passive")
		)
		(pad "95" smd rect
			(at 24.925 -1.375)
			(size 0.35 2.35)
			(layers "F.Cu" "F.Mask")
			(net 62 "unconnected-(J1-Pad95)")
			(pinfunction "CB0_A")
			(pintype "passive+no_connect")
		)
		(pad "96" smd rect
			(at 25.175 -1.375 180)
			(size 0.35 2.35)
			(layers "B.Cu" "B.Mask")
			(net 63 "unconnected-(J1-Pad96)")
			(pinfunction "CB1_A")
			(pintype "passive+no_connect")
		)
		(pad "97" smd rect
			(at 25.425 -1.375)
			(size 0.35 2.35)
			(layers "F.Cu" "F.Mask")
			(net 14 "GND")
			(pinfunction "VSS")
			(pintype "passive")
		)
		(pad "98" smd rect
			(at 25.675 -1.375 180)
			(size 0.35 2.35)
			(layers "B.Cu" "B.Mask")
			(net 14 "GND")
			(pinfunction "VSS")
			(pintype "passive")
		)
		(pad "99" smd rect
			(at 25.925 -1.375)
			(size 0.35 2.35)
			(layers "F.Cu" "F.Mask")
			(net 64 "unconnected-(J1-Pad99)")
			(pinfunction "CB2_A")
			(pintype "passive+no_connect")
		)
		(pad "100" smd rect
			(at 26.175 -1.375 180)
			(size 0.35 2.35)
			(layers "B.Cu" "B.Mask")
			(net 65 "unconnected-(J1-Pad100)")
			(pinfunction "DQS4_A_c")
			(pintype "passive+no_connect")
		)
		(pad "101" smd rect
			(at 26.425 -1.375)
			(size 0.35 2.35)
			(layers "F.Cu" "F.Mask")
			(net 14 "GND")
			(pinfunction "VSS")
			(pintype "passive")
		)
		(pad "102" smd rect
			(at 26.675 -1.375 180)
			(size 0.35 2.35)
			(layers "B.Cu" "B.Mask")
			(net 66 "unconnected-(J1-Pad102)")
			(pinfunction "DQS4_A_t")
			(pintype "passive+no_connect")
		)
		(pad "103" smd rect
			(at 26.925 -1.375)
			(size 0.35 2.35)
			(layers "F.Cu" "F.Mask")
			(net 67 "unconnected-(J1-Pad103)")
			(pinfunction "CB3_A")
			(pintype "passive+no_connect")
		)
		(pad "104" smd rect
			(at 27.175 -1.375 180)
			(size 0.35 2.35)
			(layers "B.Cu" "B.Mask")
			(net 14 "GND")
			(pinfunction "VSS")
			(pintype "passive")
		)
		(pad "105" smd rect
			(at 27.425 -1.375)
			(size 0.35 2.35)
			(layers "F.Cu" "F.Mask")
			(net 14 "GND")
			(pinfunction "VSS")
			(pintype "passive")
		)
		(pad "106" smd rect
			(at 27.675 -1.375 180)
			(size 0.35 2.35)
			(layers "B.Cu" "B.Mask")
			(net 165 "/SODIMM/LPDDR5_IN_A.CS0")
			(pinfunction "CS0_A_n")
			(pintype "passive")
		)
		(pad "107" smd rect
			(at 27.925 -1.375)
			(size 0.35 2.35)
			(layers "F.Cu" "F.Mask")
			(net 164 "/SODIMM/LPDDR5_IN_A.CA0")
			(pinfunction "CA0_A")
			(pintype "passive")
		)
		(pad "108" smd rect
			(at 28.175 -1.375 180)
			(size 0.35 2.35)
			(layers "B.Cu" "B.Mask")
			(net 68 "unconnected-(J1-Pad108)")
			(pinfunction "ALERT_n")
			(pintype "passive+no_connect")
		)
		(pad "109" smd rect
			(at 28.425 -1.375)
			(size 0.35 2.35)
			(layers "F.Cu" "F.Mask")
			(net 163 "/SODIMM/LPDDR5_IN_A.CA1")
			(pinfunction "CA1_A")
			(pintype "passive")
		)
		(pad "110" smd rect
			(at 28.675 -1.375 180)
			(size 0.35 2.35)
			(layers "B.Cu" "B.Mask")
			(net 162 "/SODIMM/LPDDR5_IN_A.CS1")
			(pinfunction "CS1_A_n")
			(pintype "passive")
		)
		(pad "111" smd rect
			(at 28.925 -1.375)
			(size 0.35 2.35)
			(layers "F.Cu" "F.Mask")
			(net 14 "GND")
			(pinfunction "VSS")
			(pintype "passive")
		)
		(pad "112" smd rect
			(at 29.175 -1.375 180)
			(size 0.35 2.35)
			(layers "B.Cu" "B.Mask")
			(net 14 "GND")
			(pinfunction "VSS")
			(pintype "passive")
		)
		(pad "113" smd rect
			(at 29.425 -1.375)
			(size 0.35 2.35)
			(layers "F.Cu" "F.Mask")
			(net 161 "/SODIMM/LPDDR5_IN_A.CA2")
			(pinfunction "CA2_A")
			(pintype "passive")
		)
		(pad "114" smd rect
			(at 29.675 -1.375 180)
			(size 0.35 2.35)
			(layers "B.Cu" "B.Mask")
			(net 160 "/SODIMM/LPDDR5_IN_A.CA3")
			(pinfunction "CA3_A")
			(pintype "passive")
		)
		(pad "115" smd rect
			(at 29.925 -1.375)
			(size 0.35 2.35)
			(layers "F.Cu" "F.Mask")
			(net 159 "/SODIMM/LPDDR5_IN_A.CA4")
			(pinfunction "CA4_A")
			(pintype "passive")
		)
		(pad "116" smd rect
			(at 30.175 -1.375 180)
			(size 0.35 2.35)
			(layers "B.Cu" "B.Mask")
			(net 158 "/SODIMM/LPDDR5_IN_A.CA5")
			(pinfunction "CA5_A")
			(pintype "passive")
		)
		(pad "117" smd rect
			(at 30.425 -1.375)
			(size 0.35 2.35)
			(layers "F.Cu" "F.Mask")
			(net 14 "GND")
			(pinfunction "VSS")
			(pintype "passive")
		)
		(pad "118" smd rect
			(at 30.675 -1.375 180)
			(size 0.35 2.35)
			(layers "B.Cu" "B.Mask")
			(net 14 "GND")
			(pinfunction "VSS")
			(pintype "passive")
		)
		(pad "119" smd rect
			(at 30.925 -1.375)
			(size 0.35 2.35)
			(layers "F.Cu" "F.Mask")
			(net 157 "/SODIMM/LPDDR5_IN_A.CA6")
			(pinfunction "CA6_A")
			(pintype "passive")
		)
		(pad "120" smd rect
			(at 31.175 -1.375 180)
			(size 0.35 2.35)
			(layers "B.Cu" "B.Mask")
			(net 74 "unconnected-(J1-Pad120)")
			(pinfunction "CA7_A")
			(pintype "passive+no_connect")
		)
		(pad "121" smd rect
			(at 31.425 -1.375)
			(size 0.35 2.35)
			(layers "F.Cu" "F.Mask")
			(net 75 "unconnected-(J1-Pad121)")
			(pinfunction "CA8_A")
			(pintype "passive+no_connect")
		)
		(pad "122" smd rect
			(at 31.675 -1.375 180)
			(size 0.35 2.35)
			(layers "B.Cu" "B.Mask")
			(net 76 "unconnected-(J1-Pad122)")
			(pinfunction "CA9_A")
			(pintype "passive+no_connect")
		)
		(pad "123" smd rect
			(at 31.925 -1.375)
			(size 0.35 2.35)
			(layers "F.Cu" "F.Mask")
			(net 14 "GND")
			(pinfunction "VSS")
			(pintype "passive")
		)
		(pad "124" smd rect
			(at 32.175 -1.375 180)
			(size 0.35 2.35)
			(layers "B.Cu" "B.Mask")
			(net 14 "GND")
			(pinfunction "VSS")
			(pintype "passive")
		)
		(pad "125" smd rect
			(at 32.425 -1.375)
			(size 0.35 2.35)
			(layers "F.Cu" "F.Mask")
			(net 77 "unconnected-(J1-Pad125)")
			(pinfunction "CA10_A")
			(pintype "passive+no_connect")
		)
		(pad "126" smd rect
			(at 32.675 -1.375 180)
			(size 0.35 2.35)
			(layers "B.Cu" "B.Mask")
			(net 78 "unconnected-(J1-Pad126)")
			(pinfunction "CA11_A")
			(pintype "passive+no_connect")
		)
		(pad "127" smd rect
			(at 34.425 -1.375)
			(size 0.35 2.35)
			(layers "F.Cu" "F.Mask")
			(net 79 "unconnected-(J1-Pad127)")
			(pinfunction "CA12_A")
			(pintype "passive+no_connect")
		)
		(pad "128" smd rect
			(at 34.675 -1.375 180)
			(size 0.35 2.35)
			(layers "B.Cu" "B.Mask")
			(net 80 "unconnected-(J1-Pad128)")
			(pinfunction "RFU")
			(pintype "passive+no_connect")
		)
		(pad "129" smd rect
			(at 34.925 -1.375)
			(size 0.35 2.35)
			(layers "F.Cu" "F.Mask")
			(net 14 "GND")
			(pinfunction "VSS")
			(pintype "passive")
		)
		(pad "130" smd rect
			(at 35.175 -1.375 180)
			(size 0.35 2.35)
			(layers "B.Cu" "B.Mask")
			(net 33 "Net-(J1-Pad130)")
			(pinfunction "TB_DETECT")
			(pintype "input")
		)
		(pad "131" smd rect
			(at 35.425 -1.375)
			(size 0.35 2.35)
			(layers "F.Cu" "F.Mask")
			(net 156 "/SODIMM/LPDDR5_IN_A.CK_P")
			(pinfunction "CK0_A_t")
			(pintype "passive")
		)
		(pad "132" smd rect
			(at 35.675 -1.375 180)
			(size 0.35 2.35)
			(layers "B.Cu" "B.Mask")
			(net 81 "unconnected-(J1-Pad132)")
			(pinfunction "CK1_A_t")
			(pintype "passive+no_connect")
		)
		(pad "133" smd rect
			(at 35.925 -1.375)
			(size 0.35 2.35)
			(layers "F.Cu" "F.Mask")
			(net 155 "/SODIMM/LPDDR5_IN_A.CK_N")
			(pinfunction "CK0_A_c")
			(pintype "passive")
		)
		(pad "134" smd rect
			(at 36.175 -1.375 180)
			(size 0.35 2.35)
			(layers "B.Cu" "B.Mask")
			(net 82 "unconnected-(J1-Pad134)")
			(pinfunction "CK1_A_c")
			(pintype "passive+no_connect")
		)
		(pad "135" smd rect
			(at 36.425 -1.375)
			(size 0.35 2.35)
			(layers "F.Cu" "F.Mask")
			(net 14 "GND")
			(pinfunction "VSS")
			(pintype "passive")
		)
		(pad "136" smd rect
			(at 36.675 -1.375 180)
			(size 0.35 2.35)
			(layers "B.Cu" "B.Mask")
			(net 14 "GND")
			(pinfunction "VSS")
			(pintype "passive")
		)
		(pad "137" smd rect
			(at 36.925 -1.375)
			(size 0.35 2.35)
			(layers "F.Cu" "F.Mask")
			(net 154 "/SODIMM/LPDDR5_IN_B.CK_P")
			(pinfunction "CK0_B_t")
			(pintype "passive")
		)
		(pad "138" smd rect
			(at 37.175 -1.375 180)
			(size 0.35 2.35)
			(layers "B.Cu" "B.Mask")
			(net 83 "unconnected-(J1-Pad138)")
			(pinfunction "CK1_B_t")
			(pintype "passive+no_connect")
		)
		(pad "139" smd rect
			(at 37.425 -1.375)
			(size 0.35 2.35)
			(layers "F.Cu" "F.Mask")
			(net 153 "/SODIMM/LPDDR5_IN_B.CK_N")
			(pinfunction "CK0_B_c")
			(pintype "passive")
		)
		(pad "140" smd rect
			(at 37.675 -1.375 180)
			(size 0.35 2.35)
			(layers "B.Cu" "B.Mask")
			(net 84 "unconnected-(J1-Pad140)")
			(pinfunction "CK1_B_C")
			(pintype "passive+no_connect")
		)
		(pad "141" smd rect
			(at 37.925 -1.375)
			(size 0.35 2.35)
			(layers "F.Cu" "F.Mask")
			(net 14 "GND")
			(pinfunction "VSS")
			(pintype "passive")
		)
		(pad "142" smd rect
			(at 38.175 -1.375 180)
			(size 0.35 2.35)
			(layers "B.Cu" "B.Mask")
			(net 14 "GND")
			(pinfunction "VSS")
			(pintype "passive")
		)
		(pad "143" smd rect
			(at 38.425 -1.375)
			(size 0.35 2.35)
			(layers "F.Cu" "F.Mask")
			(net 85 "unconnected-(J1-Pad143)")
			(pinfunction "RFU")
			(pintype "passive+no_connect")
		)
		(pad "144" smd rect
			(at 38.675 -1.375 180)
			(size 0.35 2.35)
			(layers "B.Cu" "B.Mask")
			(net 86 "unconnected-(J1-Pad144)")
			(pinfunction "CA12_B")
			(pintype "passive+no_connect")
		)
		(pad "145" smd rect
			(at 38.925 -1.375)
			(size 0.35 2.35)
			(layers "F.Cu" "F.Mask")
			(net 87 "unconnected-(J1-Pad145)")
			(pinfunction "CA11_B")
			(pintype "passive+no_connect")
		)
		(pad "146" smd rect
			(at 39.175 -1.375 180)
			(size 0.35 2.35)
			(layers "B.Cu" "B.Mask")
			(net 88 "unconnected-(J1-Pad146)")
			(pinfunction "CA10_B")
			(pintype "passive+no_connect")
		)
		(pad "147" smd rect
			(at 39.425 -1.375)
			(size 0.35 2.35)
			(layers "F.Cu" "F.Mask")
			(net 14 "GND")
			(pinfunction "VSS")
			(pintype "passive")
		)
		(pad "148" smd rect
			(at 39.675 -1.375 180)
			(size 0.35 2.35)
			(layers "B.Cu" "B.Mask")
			(net 14 "GND")
			(pinfunction "VSS")
			(pintype "passive")
		)
		(pad "149" smd rect
			(at 39.925 -1.375)
			(size 0.35 2.35)
			(layers "F.Cu" "F.Mask")
			(net 89 "unconnected-(J1-Pad149)")
			(pinfunction "CA9_B")
			(pintype "passive+no_connect")
		)
		(pad "150" smd rect
			(at 40.175 -1.375 180)
			(size 0.35 2.35)
			(layers "B.Cu" "B.Mask")
			(net 90 "unconnected-(J1-Pad150)")
			(pinfunction "CA8_B")
			(pintype "passive+no_connect")
		)
		(pad "151" smd rect
			(at 40.425 -1.375)
			(size 0.35 2.35)
			(layers "F.Cu" "F.Mask")
			(net 91 "unconnected-(J1-Pad151)")
			(pinfunction "CA7_B")
			(pintype "passive+no_connect")
		)
		(pad "152" smd rect
			(at 40.675 -1.375 180)
			(size 0.35 2.35)
			(layers "B.Cu" "B.Mask")
			(net 152 "/SODIMM/LPDDR5_IN_B.CA6")
			(pinfunction "CA6_B")
			(pintype "passive")
		)
		(pad "153" smd rect
			(at 40.925 -1.375)
			(size 0.35 2.35)
			(layers "F.Cu" "F.Mask")
			(net 14 "GND")
			(pinfunction "VSS")
			(pintype "passive")
		)
		(pad "154" smd rect
			(at 41.175 -1.375 180)
			(size 0.35 2.35)
			(layers "B.Cu" "B.Mask")
			(net 14 "GND")
			(pinfunction "VSS")
			(pintype "passive")
		)
		(pad "155" smd rect
			(at 41.425 -1.375)
			(size 0.35 2.35)
			(layers "F.Cu" "F.Mask")
			(net 151 "/SODIMM/LPDDR5_IN_B.CA5")
			(pinfunction "CA5_B")
			(pintype "passive")
		)
		(pad "156" smd rect
			(at 41.675 -1.375 180)
			(size 0.35 2.35)
			(layers "B.Cu" "B.Mask")
			(net 150 "/SODIMM/LPDDR5_IN_B.CA4")
			(pinfunction "CA4_B")
			(pintype "passive")
		)
		(pad "157" smd rect
			(at 41.925 -1.375)
			(size 0.35 2.35)
			(layers "F.Cu" "F.Mask")
			(net 149 "/SODIMM/LPDDR5_IN_B.CA3")
			(pinfunction "CA3_B")
			(pintype "passive")
		)
		(pad "158" smd rect
			(at 42.175 -1.375 180)
			(size 0.35 2.35)
			(layers "B.Cu" "B.Mask")
			(net 148 "/SODIMM/LPDDR5_IN_B.CA2")
			(pinfunction "CA2_B")
			(pintype "passive")
		)
		(pad "159" smd rect
			(at 42.425 -1.375)
			(size 0.35 2.35)
			(layers "F.Cu" "F.Mask")
			(net 14 "GND")
			(pinfunction "VSS")
			(pintype "passive")
		)
		(pad "160" smd rect
			(at 42.675 -1.375 180)
			(size 0.35 2.35)
			(layers "B.Cu" "B.Mask")
			(net 14 "GND")
			(pinfunction "VSS")
			(pintype "passive")
		)
		(pad "161" smd rect
			(at 42.925 -1.375)
			(size 0.35 2.35)
			(layers "F.Cu" "F.Mask")
			(net 147 "/SODIMM/LPDDR5_IN_B.CS0")
			(pinfunction "CS0_B_n")
			(pintype "passive")
		)
		(pad "162" smd rect
			(at 43.175 -1.375 180)
			(size 0.35 2.35)
			(layers "B.Cu" "B.Mask")
			(net 146 "/SODIMM/LPDDR5_IN_B.CA1")
			(pinfunction "CA1_B")
			(pintype "passive")
		)
		(pad "163" smd rect
			(at 43.425 -1.375)
			(size 0.35 2.35)
			(layers "F.Cu" "F.Mask")
			(net 34 "/SODIMM/~{RESET}")
			(pinfunction "RESET_n")
			(pintype "passive")
		)
		(pad "164" smd rect
			(at 43.675 -1.375 180)
			(size 0.35 2.35)
			(layers "B.Cu" "B.Mask")
			(net 145 "/SODIMM/LPDDR5_IN_B.CA0")
			(pinfunction "CA0_B")
			(pintype "passive")
		)
		(pad "165" smd rect
			(at 43.925 -1.375)
			(size 0.35 2.35)
			(layers "F.Cu" "F.Mask")
			(net 144 "/SODIMM/LPDDR5_IN_B.CS1")
			(pinfunction "CS1_B_N")
			(pintype "passive")
		)
		(pad "166" smd rect
			(at 44.175 -1.375 180)
			(size 0.35 2.35)
			(layers "B.Cu" "B.Mask")
			(net 14 "GND")
			(pinfunction "VSS")
			(pintype "passive")
		)
		(pad "167" smd rect
			(at 44.425 -1.375)
			(size 0.35 2.35)
			(layers "F.Cu" "F.Mask")
			(net 14 "GND")
			(pinfunction "VSS")
			(pintype "passive")
		)
		(pad "168" smd rect
			(at 44.675 -1.375 180)
			(size 0.35 2.35)
			(layers "B.Cu" "B.Mask")
			(net 93 "unconnected-(J1-Pad168)")
			(pinfunction "CB0_B")
			(pintype "passive+no_connect")
		)
		(pad "169" smd rect
			(at 44.925 -1.375)
			(size 0.35 2.35)
			(layers "F.Cu" "F.Mask")
			(net 94 "unconnected-(J1-Pad169)")
			(pinfunction "DQS4_B_c")
			(pintype "passive+no_connect")
		)
		(pad "170" smd rect
			(at 45.175 -1.375 180)
			(size 0.35 2.35)
			(layers "B.Cu" "B.Mask")
			(net 14 "GND")
			(pinfunction "VSS")
			(pintype "passive")
		)
		(pad "171" smd rect
			(at 45.425 -1.375)
			(size 0.35 2.35)
			(layers "F.Cu" "F.Mask")
			(net 95 "unconnected-(J1-Pad171)")
			(pinfunction "DQS4_B_T")
			(pintype "passive+no_connect")
		)
		(pad "172" smd rect
			(at 45.675 -1.375 180)
			(size 0.35 2.35)
			(layers "B.Cu" "B.Mask")
			(net 96 "unconnected-(J1-Pad172)")
			(pinfunction "CB1_B")
			(pintype "passive+no_connect")
		)
		(pad "173" smd rect
			(at 45.925 -1.375)
			(size 0.35 2.35)
			(layers "F.Cu" "F.Mask")
			(net 14 "GND")
			(pinfunction "VSS")
			(pintype "passive")
		)
		(pad "174" smd rect
			(at 46.175 -1.375 180)
			(size 0.35 2.35)
			(layers "B.Cu" "B.Mask")
			(net 14 "GND")
			(pinfunction "VSS")
			(pintype "passive")
		)
		(pad "175" smd rect
			(at 46.425 -1.375)
			(size 0.35 2.35)
			(layers "F.Cu" "F.Mask")
			(net 97 "unconnected-(J1-Pad175)")
			(pinfunction "CB3_B")
			(pintype "passive+no_connect")
		)
		(pad "176" smd rect
			(at 46.675 -1.375 180)
			(size 0.35 2.35)
			(layers "B.Cu" "B.Mask")
			(net 98 "unconnected-(J1-Pad176)")
			(pinfunction "CB2_B")
			(pintype "passive+no_connect")
		)
		(pad "177" smd rect
			(at 46.925 -1.375)
			(size 0.35 2.35)
			(layers "F.Cu" "F.Mask")
			(net 14 "GND")
			(pinfunction "VSS")
			(pintype "passive")
		)
		(pad "178" smd rect
			(at 47.175 -1.375 180)
			(size 0.35 2.35)
			(layers "B.Cu" "B.Mask")
			(net 14 "GND")
			(pinfunction "VSS")
			(pintype "passive")
		)
		(pad "179" smd rect
			(at 47.425 -1.375)
			(size 0.35 2.35)
			(layers "F.Cu" "F.Mask")
			(net 206 "/LPDDR5/LPDDR5_B.DQ8")
			(pinfunction "DQ0_B")
			(pintype "passive")
		)
		(pad "180" smd rect
			(at 47.675 -1.375 180)
			(size 0.35 2.35)
			(layers "B.Cu" "B.Mask")
			(net 208 "/LPDDR5/LPDDR5_B.DQ10")
			(pinfunction "DQ1_B")
			(pintype "passive")
		)
		(pad "181" smd rect
			(at 47.925 -1.375)
			(size 0.35 2.35)
			(layers "F.Cu" "F.Mask")
			(net 14 "GND")
			(pinfunction "VSS")
			(pintype "passive")
		)
		(pad "182" smd rect
			(at 48.175 -1.375 180)
			(size 0.35 2.35)
			(layers "B.Cu" "B.Mask")
			(net 14 "GND")
			(pinfunction "VSS")
			(pintype "passive")
		)
		(pad "183" smd rect
			(at 48.425 -1.375)
			(size 0.35 2.35)
			(layers "F.Cu" "F.Mask")
			(net 207 "/LPDDR5/LPDDR5_B.DQ9")
			(pinfunction "DQ2_B")
			(pintype "passive")
		)
		(pad "184" smd rect
			(at 48.675 -1.375 180)
			(size 0.35 2.35)
			(layers "B.Cu" "B.Mask")
			(net 209 "/LPDDR5/LPDDR5_B.DQ11")
			(pinfunction "DQ3_B")
			(pintype "passive")
		)
		(pad "185" smd rect
			(at 48.925 -1.375)
			(size 0.35 2.35)
			(layers "F.Cu" "F.Mask")
			(net 14 "GND")
			(pinfunction "VSS")
			(pintype "passive")
		)
	)
)
